# S9S_MB_2U (Grand Teton) — schematic netlist excerpt (pin names and nets, part order shuffled) for the footprints in the layout excerpt that follows; sources: Cadence DE-HDL packaged netlist, KiCad conversion of 03242023_DA0F0TMBIJ0_F0T_Motherboard_J_brd_V01_OCP.brd

R3302  Q_RES  0 5% EMPTY  pkg 0402LF  page 240 : A = TP_PCIE_HPM_TXN<3> ; B = FM_PCH_SPKR
PR836  Q_RES  1K 1% EMPTY  pkg 0402LF  page 259 : A = P3V3_AUX_VOS ; B = P3V3_AUX

(kicad_pcb
	(version 20260206)
	(generator "pcbnew")
	(generator_version "10.0")
	(general
		(thickness 1.6)
		(legacy_teardrops no)
	)
	(paper "A4")
	(title_block
		(title "03242023_DA0F0TMBIJ0_F0T_Motherboard_J_brd_V01_OCP.brd")
		(comment 1 "Grand Teton / footprints 1473-1474 of 6105")
	)
	(layers
		(0 "F.Cu" signal "TOP")
		(4 "In1.Cu" signal "GND")
		(6 "In2.Cu" signal "IN1")
		(8 "In3.Cu" signal "GND1")
		(10 "In4.Cu" signal "IN2")
		(12 "In5.Cu" signal "GND2")
		(14 "In6.Cu" signal "IN3")
		(16 "In7.Cu" signal "GND3")
		(18 "In8.Cu" signal "VCC")
		(20 "In9.Cu" signal "VCC1")
		(22 "In10.Cu" signal "GND4")
		(24 "In11.Cu" signal "IN4")
		(26 "In12.Cu" signal "GND5")
		(28 "In13.Cu" signal "IN5")
		(30 "In14.Cu" signal "GND6")
		(32 "In15.Cu" signal "IN6")
		(34 "In16.Cu" signal "GND7")
		(2 "B.Cu" signal "BOTTOM")
		(9 "F.Adhes" user "F.Adhesive")
		(11 "B.Adhes" user "B.Adhesive")
		(13 "F.Paste" user "Package Geometry/Pastemask Top")
		(15 "B.Paste" user "Package Geometry/Pastemask Bottom")
		(5 "F.SilkS" user "Ref Des/Silkscreen Top")
		(7 "B.SilkS" user "Ref Des/Silkscreen Bottom")
		(1 "F.Mask" user "Board Geometry/Soldermask Top")
		(3 "B.Mask" user "Board Geometry/Soldermask Bottom")
		(17 "Dwgs.User" user "User.Drawings")
		(19 "Cmts.User" user "User.Comments")
		(21 "Eco1.User" user "User.Eco1")
		(23 "Eco2.User" user "User.Eco2")
		(25 "Edge.Cuts" user "Board Geometry/Outline")
		(27 "Margin" user)
		(31 "F.CrtYd" user "Package Geometry/Place Bound Top")
		(29 "B.CrtYd" user "Package Geometry/Place Bound Bottom")
		(35 "F.Fab" user "Ref Des/Assembly Top")
		(33 "B.Fab" user "Ref Des/Assembly Bottom")
	)
	(footprint ""
		(layer "F.Cu")
		(at 452.486522 -76.007722)
		(property "Reference" "PR836"
			(at 0 0 0)
			(layer "F.SilkS")
			(hide yes)
			(effects
				(font
					(size 1.27 1.27)
				)
			)
		)
		(property "Value" ""
			(at 0 0 0)
			(layer "F.Fab")
			(effects
				(font
					(size 1.27 1.27)
				)
			)
		)
		(duplicate_pad_numbers_are_jumpers no)
		(fp_line
			(start -0.7874 -0.4064)
			(end 0.7874 -0.4064)
			(stroke
				(width 0.1524)
				(type default)
			)
			(layer "F.SilkS")
		)
		(fp_line
			(start -0.7874 0.4064)
			(end -0.7874 -0.4064)
			(stroke
				(width 0.1524)
				(type default)
			)
			(layer "F.SilkS")
		)
		(fp_line
			(start 0.7874 -0.4064)
			(end 0.7874 0.4064)
			(stroke
				(width 0.1524)
				(type default)
			)
			(layer "F.SilkS")
		)
		(fp_line
			(start 0.7874 0.4064)
			(end -0.7874 0.4064)
			(stroke
				(width 0.1524)
				(type default)
			)
			(layer "F.SilkS")
		)
		(fp_line
			(start -0.67945 -0.305054)
			(end -0.12065 -0.305054)
			(stroke
				(width 0.1)
				(type default)
			)
			(layer "F.Fab")
		)
		(fp_line
			(start -0.67945 0.3048)
			(end -0.67945 -0.305054)
			(stroke
				(width 0.1)
				(type default)
			)
			(layer "F.Fab")
		)
		(fp_line
			(start -0.12065 -0.305054)
			(end -0.12065 -0.2794)
			(stroke
				(width 0.1)
				(type default)
			)
			(layer "F.Fab")
		)
		(fp_line
			(start -0.12065 -0.2794)
			(end 0.12065 -0.2794)
			(stroke
				(width 0.1)
				(type default)
			)
			(layer "F.Fab")
		)
		(fp_line
			(start -0.12065 0.2794)
			(end -0.12065 0.3048)
			(stroke
				(width 0.1)
				(type default)
			)
			(layer "F.Fab")
		)
		(fp_line
			(start -0.12065 0.3048)
			(end -0.67945 0.3048)
			(stroke
				(width 0.1)
				(type default)
			)
			(layer "F.Fab")
		)
		(fp_line
			(start 0.120396 0.2794)
			(end -0.12065 0.2794)
			(stroke
				(width 0.1)
				(type default)
			)
			(layer "F.Fab")
		)
		(fp_line
			(start 0.120396 0.3048)
			(end 0.120396 0.2794)
			(stroke
				(width 0.1)
				(type default)
			)
			(layer "F.Fab")
		)
		(fp_line
			(start 0.12065 -0.3048)
			(end 0.67945 -0.3048)
			(stroke
				(width 0.1)
				(type default)
			)
			(layer "F.Fab")
		)
		(fp_line
			(start 0.12065 -0.2794)
			(end 0.12065 -0.3048)
			(stroke
				(width 0.1)
				(type default)
			)
			(layer "F.Fab")
		)
		(fp_line
			(start 0.67945 -0.3048)
			(end 0.67945 0.3048)
			(stroke
				(width 0.1)
				(type default)
			)
			(layer "F.Fab")
		)
		(fp_line
			(start 0.67945 0.3048)
			(end 0.120396 0.3048)
			(stroke
				(width 0.1)
				(type default)
			)
			(layer "F.Fab")
		)
		(pad "1" smd circle
			(at -0.40005 0)
			(size 0 0)
			(layers "F.Cu" "F.Mask" "F.Paste")
			(net "P3V3_AUX_VOS")
		)
		(pad "2" smd circle
			(at 0.40005 0)
			(size 0 0)
			(layers "F.Cu" "F.Mask" "F.Paste")
			(net "P3V3_AUX")
		)
	)
	(footprint ""
		(layer "F.Cu")
		(at 130.10388 -21.554948 90)
		(property "Reference" "R3302"
			(at 0 0 90)
			(layer "F.SilkS")
			(hide yes)
			(effects
				(font
					(size 1.27 1.27)
				)
			)
		)
		(property "Value" ""
			(at 0 0 90)
			(layer "F.Fab")
			(effects
				(font
					(size 1.27 1.27)
				)
			)
		)
		(duplicate_pad_numbers_are_jumpers no)
		(fp_line
			(start 0.7874 -0.4064)
			(end 0.7874 0.4064)
			(stroke
				(width 0.1524)
				(type default)
			)
			(layer "F.SilkS")
		)
		(fp_line
			(start -0.7874 -0.4064)
			(end 0.7874 -0.4064)
			(stroke
				(width 0.1524)
				(type default)
			)
			(layer "F.SilkS")
		)
		(fp_line
			(start 0.7874 0.4064)
			(end -0.7874 0.4064)
			(stroke
				(width 0.1524)
				(type default)
			)
			(layer "F.SilkS")
		)
		(fp_line
			(start -0.7874 0.4064)
			(end -0.7874 -0.4064)
			(stroke
				(width 0.1524)
				(type default)
			)
			(layer "F.SilkS")
		)
		(fp_line
			(start -0.12065 -0.305054)
			(end -0.12065 -0.2794)
			(stroke
				(width 0.1)
				(type default)
			)
			(layer "F.Fab")
		)
		(fp_line
			(start -0.67945 -0.305054)
			(end -0.12065 -0.305054)
			(stroke
				(width 0.1)
				(type default)
			)
			(layer "F.Fab")
		)
		(fp_line
			(start 0.67945 -0.3048)
			(end 0.67945 0.3048)
			(stroke
				(width 0.1)
				(type default)
			)
			(layer "F.Fab")
		)
		(fp_line
			(start 0.12065 -0.3048)
			(end 0.67945 -0.3048)
			(stroke
				(width 0.1)
				(type default)
			)
			(layer "F.Fab")
		)
		(fp_line
			(start 0.12065 -0.2794)
			(end 0.12065 -0.3048)
			(stroke
				(width 0.1)
				(type default)
			)
			(layer "F.Fab")
		)
		(fp_line
			(start -0.12065 -0.2794)
			(end 0.12065 -0.2794)
			(stroke
				(width 0.1)
				(type default)
			)
			(layer "F.Fab")
		)
		(fp_line
			(start 0.120396 0.2794)
			(end -0.12065 0.2794)
			(stroke
				(width 0.1)
				(type default)
			)
			(layer "F.Fab")
		)
		(fp_line
			(start -0.12065 0.2794)
			(end -0.12065 0.3048)
			(stroke
				(width 0.1)
				(type default)
			)
			(layer "F.Fab")
		)
		(fp_line
			(start 0.67945 0.3048)
			(end 0.120396 0.3048)
			(stroke
				(width 0.1)
				(type default)
			)
			(layer "F.Fab")
		)
		(fp_line
			(start 0.120396 0.3048)
			(end 0.120396 0.2794)
			(stroke
				(width 0.1)
				(type default)
			)
			(layer "F.Fab")
		)
		(fp_line
			(start -0.12065 0.3048)
			(end -0.67945 0.3048)
			(stroke
				(width 0.1)
				(type default)
			)
			(layer "F.Fab")
		)
		(fp_line
			(start -0.67945 0.3048)
			(end -0.67945 -0.305054)
			(stroke
				(width 0.1)
				(type default)
			)
			(layer "F.Fab")
		)
		(pad "1" smd circle
			(at -0.40005 0 90)
			(size 0 0)
			(layers "F.Cu" "F.Mask" "F.Paste")
			(net "TP_PCIE_HPM_TXN<3>")
		)
		(pad "2" smd circle
			(at 0.40005 0 90)
			(size 0 0)
			(layers "F.Cu" "F.Mask" "F.Paste")
			(net "FM_PCH_SPKR")
		)
	)
)
